# T6G (Grand Teton) — schematic netlist excerpt (pin names and nets, part order shuffled) for the footprints in the layout excerpt that follows; sources: Cadence DE-HDL packaged netlist, KiCad conversion of 04192023_DAF0TMB3IC0_F0TG_MB_C_brd_V02_OCP.brd

C6022  Q_CAP_DIFFBUS  DIFF BUS_0.33UF 6.3V 10% X6S  pkg C0402  page 180 : \1\ = USB3_CPU0_BMC_RX_DN ; \2\ = USB3_CPU0_BMC_RX_C2_DN
R2793  Q_RES  0 5% CHIP  pkg 0402LF  page 240 : A = FM_PDB_BUF_EN_R_N ; B = FM_PDB_BUF_EN_R1_N
C956  Q_CAP_DIFFBUS  DIFF BUS_0.22UF 6.3V 20% X6S  pkg C0201  page 63 : \1\ = P5E_CPU0_P1_TX_C_DN<4> ; \2\ = P5E_CPU0_P1_TX_DN<4>

(kicad_pcb
	(version 20260206)
	(generator "pcbnew")
	(generator_version "10.0")
	(general
		(thickness 1.6)
		(legacy_teardrops no)
	)
	(paper "A4")
	(title_block
		(title "04192023_DAF0TMB3IC0_F0TG_MB_C_brd_V02_OCP.brd")
		(comment 1 "Grand Teton / footprints 1204-1206 of 8354")
	)
	(layers
		(0 "F.Cu" signal "TOP")
		(4 "In1.Cu" signal "GND")
		(6 "In2.Cu" signal "IN1")
		(8 "In3.Cu" signal "GND1")
		(10 "In4.Cu" signal "IN2")
		(12 "In5.Cu" signal "GND2")
		(14 "In6.Cu" signal "IN3")
		(16 "In7.Cu" signal "GND3")
		(18 "In8.Cu" signal "VCC")
		(20 "In9.Cu" signal "VCC1")
		(22 "In10.Cu" signal "GND4")
		(24 "In11.Cu" signal "IN4")
		(26 "In12.Cu" signal "GND5")
		(28 "In13.Cu" signal "IN5")
		(30 "In14.Cu" signal "GND6")
		(32 "In15.Cu" signal "IN6")
		(34 "In16.Cu" signal "GND7")
		(2 "B.Cu" signal "BOTTOM")
		(9 "F.Adhes" user "F.Adhesive")
		(11 "B.Adhes" user "B.Adhesive")
		(13 "F.Paste" user "Package Geometry/Pastemask Top")
		(15 "B.Paste" user "Package Geometry/Pastemask Bottom")
		(5 "F.SilkS" user "Ref Des/Silkscreen Top")
		(7 "B.SilkS" user "Ref Des/Silkscreen Bottom")
		(1 "F.Mask" user "Board Geometry/Soldermask Top")
		(3 "B.Mask" user "Board Geometry/Soldermask Bottom")
		(17 "Dwgs.User" user "User.Drawings")
		(19 "Cmts.User" user "User.Comments")
		(21 "Eco1.User" user "User.Eco1")
		(23 "Eco2.User" user "User.Eco2")
		(25 "Edge.Cuts" user "Board Geometry/Outline")
		(27 "Margin" user)
		(31 "F.CrtYd" user "Package Geometry/Place Bound Top")
		(29 "B.CrtYd" user "Package Geometry/Place Bound Bottom")
		(35 "F.Fab" user "Ref Des/Assembly Top")
		(33 "B.Fab" user "Ref Des/Assembly Bottom")
	)
	(footprint ""
		(layer "F.Cu")
		(at 337.537044 -383.88163 -90)
		(property "Reference" "C956"
			(at 0 0 270)
			(layer "F.SilkS")
			(hide yes)
			(effects
				(font
					(size 1.27 1.27)
				)
			)
		)
		(property "Value" ""
			(at 0 0 270)
			(layer "F.Fab")
			(effects
				(font
					(size 1.27 1.27)
				)
			)
		)
		(duplicate_pad_numbers_are_jumpers no)
		(fp_line
			(start -0.299974 0.150114)
			(end -0.299974 -0.150114)
			(stroke
				(width 0.1)
				(type default)
			)
			(layer "F.Fab")
		)
		(fp_line
			(start 0.299974 0.150114)
			(end -0.299974 0.150114)
			(stroke
				(width 0.1)
				(type default)
			)
			(layer "F.Fab")
		)
		(fp_line
			(start -0.299974 -0.150114)
			(end 0.299974 -0.150114)
			(stroke
				(width 0.1)
				(type default)
			)
			(layer "F.Fab")
		)
		(fp_line
			(start 0.299974 -0.150114)
			(end 0.299974 0.150114)
			(stroke
				(width 0.1)
				(type default)
			)
			(layer "F.Fab")
		)
		(pad "1" smd rect
			(at -0.2667 0 270)
			(size 0.3048 0.381)
			(layers "F.Cu" "F.Mask" "F.Paste")
			(net "P5E_CPU0_P1_TX_C_DN<4>")
		)
		(pad "2" smd rect
			(at 0.2667 0 270)
			(size 0.3048 0.381)
			(layers "F.Cu" "F.Mask" "F.Paste")
			(net "P5E_CPU0_P1_TX_DN<4>")
		)
	)
	(footprint ""
		(layer "F.Cu")
		(at 192.700148 -430.115726)
		(property "Reference" "R2793"
			(at 0 0 0)
			(layer "F.SilkS")
			(hide yes)
			(effects
				(font
					(size 1.27 1.27)
				)
			)
		)
		(property "Value" ""
			(at 0 0 0)
			(layer "F.Fab")
			(effects
				(font
					(size 1.27 1.27)
				)
			)
		)
		(duplicate_pad_numbers_are_jumpers no)
		(fp_line
			(start -0.7874 -0.4064)
			(end 0.7874 -0.4064)
			(stroke
				(width 0.1524)
				(type default)
			)
			(layer "F.SilkS")
		)
		(fp_line
			(start -0.7874 0.4064)
			(end -0.7874 -0.4064)
			(stroke
				(width 0.1524)
				(type default)
			)
			(layer "F.SilkS")
		)
		(fp_line
			(start 0.7874 -0.4064)
			(end 0.7874 0.4064)
			(stroke
				(width 0.1524)
				(type default)
			)
			(layer "F.SilkS")
		)
		(fp_line
			(start 0.7874 0.4064)
			(end -0.7874 0.4064)
			(stroke
				(width 0.1524)
				(type default)
			)
			(layer "F.SilkS")
		)
		(fp_line
			(start -0.67945 -0.305054)
			(end -0.12065 -0.305054)
			(stroke
				(width 0.1)
				(type default)
			)
			(layer "F.Fab")
		)
		(fp_line
			(start -0.67945 0.3048)
			(end -0.67945 -0.305054)
			(stroke
				(width 0.1)
				(type default)
			)
			(layer "F.Fab")
		)
		(fp_line
			(start -0.12065 -0.305054)
			(end -0.12065 -0.2794)
			(stroke
				(width 0.1)
				(type default)
			)
			(layer "F.Fab")
		)
		(fp_line
			(start -0.12065 -0.2794)
			(end 0.12065 -0.2794)
			(stroke
				(width 0.1)
				(type default)
			)
			(layer "F.Fab")
		)
		(fp_line
			(start -0.12065 0.2794)
			(end -0.12065 0.3048)
			(stroke
				(width 0.1)
				(type default)
			)
			(layer "F.Fab")
		)
		(fp_line
			(start -0.12065 0.3048)
			(end -0.67945 0.3048)
			(stroke
				(width 0.1)
				(type default)
			)
			(layer "F.Fab")
		)
		(fp_line
			(start 0.120396 0.2794)
			(end -0.12065 0.2794)
			(stroke
				(width 0.1)
				(type default)
			)
			(layer "F.Fab")
		)
		(fp_line
			(start 0.120396 0.3048)
			(end 0.120396 0.2794)
			(stroke
				(width 0.1)
				(type default)
			)
			(layer "F.Fab")
		)
		(fp_line
			(start 0.12065 -0.3048)
			(end 0.67945 -0.3048)
			(stroke
				(width 0.1)
				(type default)
			)
			(layer "F.Fab")
		)
		(fp_line
			(start 0.12065 -0.2794)
			(end 0.12065 -0.3048)
			(stroke
				(width 0.1)
				(type default)
			)
			(layer "F.Fab")
		)
		(fp_line
			(start 0.67945 -0.3048)
			(end 0.67945 0.3048)
			(stroke
				(width 0.1)
				(type default)
			)
			(layer "F.Fab")
		)
		(fp_line
			(start 0.67945 0.3048)
			(end 0.120396 0.3048)
			(stroke
				(width 0.1)
				(type default)
			)
			(layer "F.Fab")
		)
		(pad "1" smd circle
			(at -0.40005 0)
			(size 0 0)
			(layers "F.Cu" "F.Mask" "F.Paste")
			(net "FM_PDB_BUF_EN_R_N")
		)
		(pad "2" smd circle
			(at 0.40005 0)
			(size 0 0)
			(layers "F.Cu" "F.Mask" "F.Paste")
			(net "FM_PDB_BUF_EN_R1_N")
		)
	)
	(footprint ""
		(layer "F.Cu")
		(at 124.58827 -34.021268 180)
		(property "Reference" "C6022"
			(at 0 0 180)
			(layer "F.SilkS")
			(hide yes)
			(effects
				(font
					(size 1.27 1.27)
				)
			)
		)
		(property "Value" ""
			(at 0 0 180)
			(layer "F.Fab")
			(effects
				(font
					(size 1.27 1.27)
				)
			)
		)
		(duplicate_pad_numbers_are_jumpers no)
		(fp_line
			(start 0.40005 0.4064)
			(end -0.40005 0.4064)
			(stroke
				(width 0.1524)
				(type default)
			)
			(layer "F.SilkS")
		)
		(fp_line
			(start -0.40005 -0.4064)
			(end 0.40005 -0.4064)
			(stroke
				(width 0.1524)
				(type default)
			)
			(layer "F.SilkS")
		)
		(fp_line
			(start 0.6858 0.3048)
			(end 0.1016 0.3048)
			(stroke
				(width 0.1)
				(type default)
			)
			(layer "F.Fab")
		)
		(fp_line
			(start 0.6858 -0.3048)
			(end 0.6858 0.3048)
			(stroke
				(width 0.1)
				(type default)
			)
			(layer "F.Fab")
		)
		(fp_line
			(start 0.1016 0.3048)
			(end 0.1016 0.2794)
			(stroke
				(width 0.1)
				(type default)
			)
			(layer "F.Fab")
		)
		(fp_line
			(start 0.1016 0.2794)
			(end -0.1016 0.2794)
			(stroke
				(width 0.1)
				(type default)
			)
			(layer "F.Fab")
		)
		(fp_line
			(start 0.1016 -0.2794)
			(end 0.1016 -0.3048)
			(stroke
				(width 0.1)
				(type default)
			)
			(layer "F.Fab")
		)
		(fp_line
			(start 0.1016 -0.3048)
			(end 0.6858 -0.3048)
			(stroke
				(width 0.1)
				(type default)
			)
			(layer "F.Fab")
		)
		(fp_line
			(start -0.1016 0.3048)
			(end -0.6858 0.3048)
			(stroke
				(width 0.1)
				(type default)
			)
			(layer "F.Fab")
		)
		(fp_line
			(start -0.1016 0.2794)
			(end -0.1016 0.3048)
			(stroke
				(width 0.1)
				(type default)
			)
			(layer "F.Fab")
		)
		(fp_line
			(start -0.1016 -0.2794)
			(end 0.1016 -0.2794)
			(stroke
				(width 0.1)
				(type default)
			)
			(layer "F.Fab")
		)
		(fp_line
			(start -0.1016 -0.3048)
			(end -0.1016 -0.2794)
			(stroke
				(width 0.1)
				(type default)
			)
			(layer "F.Fab")
		)
		(fp_line
			(start -0.6858 0.3048)
			(end -0.6858 -0.3048)
			(stroke
				(width 0.1)
				(type default)
			)
			(layer "F.Fab")
		)
		(fp_line
			(start -0.6858 -0.3048)
			(end -0.1016 -0.3048)
			(stroke
				(width 0.1)
				(type default)
			)
			(layer "F.Fab")
		)
		(pad "1" smd rect
			(at -0.40005 0)
			(size 0.4572 0.508)
			(layers "F.Cu" "F.Mask" "F.Paste")
			(net "USB3_CPU0_BMC_RX_DN")
		)
		(pad "2" smd rect
			(at 0.40005 0)
			(size 0.4572 0.508)
			(layers "F.Cu" "F.Mask" "F.Paste")
			(net "USB3_CPU0_BMC_RX_C2_DN")
		)
	)
)
